(kicad_pcb
	(version 20241229)
	(generator "pcbnew")
	(generator_version "9.0")
	(general
		(thickness 1.59)
		(legacy_teardrops no)
	)
	(paper "A3")
	(title_block
		(title "usb-c-power-adapter")
		(date "2025-06-24")
		(rev "1.1.2")
		(company "Antmicro")
		(comment 9 "footprints 33-37 of 122")
	)
	(layers
		(0 "F.Cu" signal)
		(4 "In1.Cu" signal)
		(6 "In2.Cu" signal)
		(2 "B.Cu" signal)
		(9 "F.Adhes" user "F.Adhesive")
		(11 "B.Adhes" user "B.Adhesive")
		(13 "F.Paste" user)
		(15 "B.Paste" user)
		(5 "F.SilkS" user "F.Silkscreen")
		(7 "B.SilkS" user "B.Silkscreen")
		(1 "F.Mask" user)
		(3 "B.Mask" user)
		(17 "Dwgs.User" user "User.Drawings")
		(19 "Cmts.User" user "User.Comments")
		(21 "Eco1.User" user "User.Eco1")
		(23 "Eco2.User" user "User.Eco2")
		(25 "Edge.Cuts" user)
		(27 "Margin" user)
		(31 "F.CrtYd" user "F.Courtyard")
		(29 "B.CrtYd" user "B.Courtyard")
		(35 "F.Fab" user)
		(33 "B.Fab" user)
	)
	(footprint "antmicro-footprints:R_0402_1005Metric"
		(layer "F.Cu")
		(at 82.35 69.75 90)
		(descr "Resistor SMD 0402")
		(tags "resistor SMD 0402")
		(property "Reference" "R32"
			(at 1.17 0.454 90)
			(layer "F.SilkS")
			(effects
				(font
					(size 0.7 0.7)
					(thickness 0.15)
				)
				(justify left bottom)
			)
		)
		(property "Value" "R_4k7_0402"
			(at -1.011843 1.772047 90)
			(layer "F.Fab")
			(effects
				(font
					(size 0.7 0.7)
					(thickness 0.15)
				)
				(justify left bottom)
			)
		)
		(property "Datasheet" "https://www.bourns.com/docs/product-datasheets/cr.pdf"
			(at 0 0 90)
			(layer "F.Fab")
			(hide yes)
			(effects
				(font
					(size 1.27 1.27)
					(thickness 0.15)
				)
			)
		)
		(property "Description" "SMD Chip Resistor, 4.7 kohm, ± 1%, 62.5 mW, 0402 [1005 Metric], Thick Film, General Purpose"
			(at 0 0 90)
			(layer "F.Fab")
			(hide yes)
			(effects
				(font
					(size 1.27 1.27)
					(thickness 0.15)
				)
			)
		)
		(property "MPN" "CR0402-FX-4701GLF"
			(at 0 0 90)
			(unlocked yes)
			(layer "F.Fab")
			(hide yes)
			(effects
				(font
					(size 1 1)
					(thickness 0.15)
				)
			)
		)
		(property "Manufacturer" "Bourns"
			(at 0 0 90)
			(unlocked yes)
			(layer "F.Fab")
			(hide yes)
			(effects
				(font
					(size 1 1)
					(thickness 0.15)
				)
			)
		)
		(property "License" "Apache-2.0"
			(at 0 0 90)
			(unlocked yes)
			(layer "F.Fab")
			(hide yes)
			(effects
				(font
					(size 1 1)
					(thickness 0.15)
				)
			)
		)
		(property "Author" "Antmicro"
			(at 0 0 90)
			(unlocked yes)
			(layer "F.Fab")
			(hide yes)
			(effects
				(font
					(size 1 1)
					(thickness 0.15)
				)
			)
		)
		(property "Val" "4k7"
			(at 0 0 90)
			(unlocked yes)
			(layer "F.Fab")
			(hide yes)
			(effects
				(font
					(size 1 1)
					(thickness 0.15)
				)
			)
		)
		(property "Tolerance" "1%"
			(at 0 0 90)
			(unlocked yes)
			(layer "F.Fab")
			(hide yes)
			(effects
				(font
					(size 1 1)
					(thickness 0.15)
				)
			)
		)
		(sheetname "/USB PD/")
		(sheetfile "usb_pd.kicad_sch")
		(attr smd exclude_from_pos_files exclude_from_bom dnp)
		(fp_rect
			(start -0.925 -0.47)
			(end 0.925 0.47)
			(stroke
				(width 0.05)
				(type default)
			)
			(fill no)
			(layer "F.CrtYd")
		)
		(fp_rect
			(start -0.5 -0.25)
			(end 0.5 0.25)
			(stroke
				(width 0.15)
				(type solid)
			)
			(fill no)
			(layer "F.Fab")
		)
		(pad "1" smd roundrect
			(at -0.48 0 90)
			(size 0.59 0.64)
			(layers "F.Cu" "F.Mask" "F.Paste")
			(roundrect_rratio 0.25)
			(net 37 "/USB PD/SDA")
			(pintype "passive")
		)
		(pad "2" smd roundrect
			(at 0.48 0 90)
			(size 0.59 0.64)
			(layers "F.Cu" "F.Mask" "F.Paste")
			(roundrect_rratio 0.25)
			(net 1 "+3V3")
			(pintype "passive")
		)
	)
	(footprint "antmicro-footprints:C_Pol_Vishay-T59-EE"
		(layer "F.Cu")
		(at 90.676 95.55 -90)
		(property "Reference" "C43"
			(at -4.95 3.676 0)
			(unlocked yes)
			(layer "F.SilkS")
			(effects
				(font
					(size 0.7 0.7)
					(thickness 0.15)
				)
				(justify left bottom)
			)
		)
		(property "Value" "C_Pol_150u_30V_Vishay-T59-EE"
			(at -5.08 5.08 270)
			(unlocked yes)
			(layer "F.Fab")
			(effects
				(font
					(size 0.7 0.7)
					(thickness 0.15)
				)
				(justify left bottom)
			)
		)
		(property "Datasheet" "https://www.vishay.com/docs/40191/t59.pdf"
			(at 0 0 270)
			(layer "F.Fab")
			(hide yes)
			(effects
				(font
					(size 1.27 1.27)
					(thickness 0.15)
				)
			)
		)
		(property "Description" "Tantalum Capacitors - Polymer 150uF 30volts 20% 75mohms maxESR"
			(at 0 0 270)
			(layer "F.Fab")
			(hide yes)
			(effects
				(font
					(size 1.27 1.27)
					(thickness 0.15)
				)
			)
		)
		(property "MPN" "T59EE157M030C0075"
			(at 0 0 270)
			(unlocked yes)
			(layer "F.Fab")
			(hide yes)
			(effects
				(font
					(size 1 1)
					(thickness 0.15)
				)
			)
		)
		(property "Manufacturer" "Vishay"
			(at 0 0 270)
			(unlocked yes)
			(layer "F.Fab")
			(hide yes)
			(effects
				(font
					(size 1 1)
					(thickness 0.15)
				)
			)
		)
		(property "Voltage" "30V"
			(at 0 0 270)
			(unlocked yes)
			(layer "F.Fab")
			(hide yes)
			(effects
				(font
					(size 1 1)
					(thickness 0.15)
				)
			)
		)
		(property "Val" "150u"
			(at 0 0 270)
			(unlocked yes)
			(layer "F.Fab")
			(hide yes)
			(effects
				(font
					(size 1 1)
					(thickness 0.15)
				)
			)
		)
		(property "Author" "Antmicro"
			(at 0 0 270)
			(unlocked yes)
			(layer "F.Fab")
			(hide yes)
			(effects
				(font
					(size 1 1)
					(thickness 0.15)
				)
			)
		)
		(property "License" "Apache-2.0"
			(at 0 0 270)
			(unlocked yes)
			(layer "F.Fab")
			(hide yes)
			(effects
				(font
					(size 1 1)
					(thickness 0.15)
				)
			)
		)
		(property "Dielectric" "template_dielectric"
			(at 0 0 270)
			(unlocked yes)
			(layer "F.Fab")
			(hide yes)
			(effects
				(font
					(size 1 1)
					(thickness 0.15)
				)
			)
		)
		(sheetname "/DC-DC Converters/")
		(sheetfile "dc-dc_converters.kicad_sch")
		(attr smd)
		(fp_line
			(start -2 2.25)
			(end 2 2.25)
			(stroke
				(width 0.15)
				(type solid)
			)
			(layer "F.SilkS")
		)
		(fp_line
			(start -2 -2.25)
			(end 2 -2.25)
			(stroke
				(width 0.15)
				(type solid)
			)
			(layer "F.SilkS")
		)
		(fp_line
			(start -3.5 -2.8)
			(end -3.5 -3.2)
			(stroke
				(width 0.15)
				(type solid)
			)
			(layer "F.SilkS")
		)
		(fp_line
			(start -3.7 -3)
			(end -3.3 -3)
			(stroke
				(width 0.15)
				(type solid)
			)
			(layer "F.SilkS")
		)
		(fp_rect
			(start -4.9 -2.9)
			(end 4.9 2.9)
			(stroke
				(width 0.05)
				(type solid)
			)
			(fill no)
			(layer "F.CrtYd")
		)
		(fp_rect
			(start -3.75 -2.25)
			(end 3.75 2.25)
			(stroke
				(width 0.15)
				(type solid)
			)
			(fill no)
			(layer "F.Fab")
		)
		(pad "1" smd trapezoid
			(at -3.4 0 270)
			(size 2.5 5.3)
			(layers "F.Cu" "F.Mask" "F.Paste")
			(net 12 "Net-(U2-V_{CIN})")
			(pintype "passive")
		)
		(pad "2" smd trapezoid
			(at 3.4 0 270)
			(size 2.5 5.3)
			(layers "F.Cu" "F.Mask" "F.Paste")
			(net 2 "GND")
			(pintype "passive")
		)
	)
	(footprint "antmicro-footprints:FB_1206_3216Metric"
		(layer "F.Cu")
		(at 85.35 83.05 -90)
		(property "Reference" "FB1"
			(at 3.16 -1.046 180)
			(layer "F.SilkS")
			(effects
				(font
					(size 0.7 0.7)
					(thickness 0.15)
				)
				(justify right bottom)
			)
		)
		(property "Value" "FB_10Z_10A_WE-MPSB_1206"
			(at 0 2 90)
			(layer "F.Fab")
			(effects
				(font
					(size 0.7 0.7)
					(thickness 0.15)
				)
				(justify right bottom)
			)
		)
		(property "Datasheet" "https://www.we-online.com/catalog/datasheet/74279221100.pdf"
			(at 0 0 270)
			(layer "F.Fab")
			(hide yes)
			(effects
				(font
					(size 1.27 1.27)
					(thickness 0.15)
				)
			)
		)
		(property "Description" "Ferrite Bead, 1206 [3216 Metric], 10 ohm, 10.5 A, WE-MPSB, 0.003 ohm, ± 25%, High Current"
			(at 0 0 270)
			(layer "F.Fab")
			(hide yes)
			(effects
				(font
					(size 1.27 1.27)
					(thickness 0.15)
				)
			)
		)
		(property "MPN" "74279221100"
			(at 0 0 270)
			(unlocked yes)
			(layer "F.Fab")
			(hide yes)
			(effects
				(font
					(size 1 1)
					(thickness 0.15)
				)
			)
		)
		(property "Manufacturer" "Würth Elektronik"
			(at 0 0 270)
			(unlocked yes)
			(layer "F.Fab")
			(hide yes)
			(effects
				(font
					(size 1 1)
					(thickness 0.15)
				)
			)
		)
		(property "Author" "Antmicro"
			(at 0 0 270)
			(unlocked yes)
			(layer "F.Fab")
			(hide yes)
			(effects
				(font
					(size 1 1)
					(thickness 0.15)
				)
			)
		)
		(property "License" "Apache-2.0"
			(at 0 0 270)
			(unlocked yes)
			(layer "F.Fab")
			(hide yes)
			(effects
				(font
					(size 1 1)
					(thickness 0.15)
				)
			)
		)
		(property "Val" "10Z/10A"
			(at 0 0 270)
			(unlocked yes)
			(layer "F.Fab")
			(hide yes)
			(effects
				(font
					(size 1 1)
					(thickness 0.15)
				)
			)
		)
		(property "Current" ""
			(at 0 0 270)
			(unlocked yes)
			(layer "F.Fab")
			(hide yes)
			(effects
				(font
					(size 1 1)
					(thickness 0.15)
				)
			)
		)
		(sheetname "/DC-DC Converters/")
		(sheetfile "dc-dc_converters.kicad_sch")
		(attr smd)
		(fp_line
			(start 0.8 0.901)
			(end -0.8 0.901)
			(stroke
				(width 0.15)
				(type solid)
			)
			(layer "F.SilkS")
		)
		(fp_line
			(start 0.8 -0.899)
			(end -0.8 -0.899)
			(stroke
				(width 0.15)
				(type solid)
			)
			(layer "F.SilkS")
		)
		(fp_rect
			(start -2.325 -1.15)
			(end 2.325 1.15)
			(stroke
				(width 0.05)
				(type default)
			)
			(fill no)
			(layer "F.CrtYd")
		)
		(fp_line
			(start -1.677 0.792)
			(end -1.677 -0.861)
			(stroke
				(width 0.15)
				(type solid)
			)
			(layer "F.Fab")
		)
		(fp_line
			(start 1.624 0.792)
			(end -1.677 0.792)
			(stroke
				(width 0.15)
				(type solid)
			)
			(layer "F.Fab")
		)
		(fp_line
			(start -1.677 -0.861)
			(end 1.624 -0.861)
			(stroke
				(width 0.15)
				(type solid)
			)
			(layer "F.Fab")
		)
		(fp_line
			(start 1.624 -0.861)
			(end 1.624 0.792)
			(stroke
				(width 0.15)
				(type solid)
			)
			(layer "F.Fab")
		)
		(pad "1" smd roundrect
			(at -1.5 0.001 270)
			(size 1.15 1.8)
			(layers "F.Cu" "F.Mask" "F.Paste")
			(roundrect_rratio 0.25)
			(net 3 "VCC")
			(pintype "passive")
		)
		(pad "2" smd roundrect
			(at 1.5 0.001 270)
			(size 1.15 1.8)
			(layers "F.Cu" "F.Mask" "F.Paste")
			(roundrect_rratio 0.25)
			(net 12 "Net-(U2-V_{CIN})")
			(pintype "passive")
		)
	)
	(footprint "antmicro-footprints:LED_0603_1608Metric_G"
		(layer "F.Cu")
		(at 98.35 74.55 90)
		(descr "LED SMD 0603 Green")
		(tags "LED SMD 0603 Green")
		(property "Reference" "D6"
			(at -6.8 0.126 0)
			(layer "B.SilkS")
			(effects
				(font
					(size 0.7 0.7)
					(thickness 0.15)
				)
				(justify right bottom mirror)
			)
		)
		(property "Value" "LED_G_0603_LG_L29K-G2J1-24-Z"
			(at -0.001 1.599 90)
			(layer "F.Fab")
			(effects
				(font
					(size 0.7 0.7)
					(thickness 0.15)
				)
				(justify left bottom)
			)
		)
		(property "Datasheet" "https://look.ams-osram.com/m/19ee86b3ae0ee95b/original/LG-L29K.pdf"
			(at 0 0 90)
			(layer "F.Fab")
			(hide yes)
			(effects
				(font
					(size 1.27 1.27)
					(thickness 0.15)
				)
			)
		)
		(property "Description" "LED, Green, SMD, 0603, 20 mA, 1.7 V, 570 nm"
			(at 0 0 90)
			(layer "F.Fab")
			(hide yes)
			(effects
				(font
					(size 1.27 1.27)
					(thickness 0.15)
				)
			)
		)
		(property "MPN" "LG L29K-G2J1-24-Z"
			(at 0 0 90)
			(unlocked yes)
			(layer "F.Fab")
			(hide yes)
			(effects
				(font
					(size 1 1)
					(thickness 0.15)
				)
			)
		)
		(property "Manufacturer" "OSRAM"
			(at 0 0 90)
			(unlocked yes)
			(layer "F.Fab")
			(hide yes)
			(effects
				(font
					(size 1 1)
					(thickness 0.15)
				)
			)
		)
		(property "Color" "Green"
			(at 0 0 90)
			(unlocked yes)
			(layer "F.Fab")
			(hide yes)
			(effects
				(font
					(size 1 1)
					(thickness 0.15)
				)
			)
		)
		(property "Author" "Antmicro"
			(at 0 0 90)
			(unlocked yes)
			(layer "F.Fab")
			(hide yes)
			(effects
				(font
					(size 1 1)
					(thickness 0.15)
				)
			)
		)
		(property "License" "Apache-2.0"
			(at 0 0 90)
			(unlocked yes)
			(layer "F.Fab")
			(hide yes)
			(effects
				(font
					(size 1 1)
					(thickness 0.15)
				)
			)
		)
		(sheetname "/USB PD/")
		(sheetfile "usb_pd.kicad_sch")
		(attr smd)
		(fp_line
			(start 0.22 -0.35)
			(end -0.22 -0.35)
			(stroke
				(width 0.15)
				(type solid)
			)
			(layer "F.SilkS")
		)
		(fp_line
			(start -1.18 -0.319)
			(end -1.18 0.321)
			(stroke
				(width 0.15)
				(type solid)
			)
			(layer "F.SilkS")
		)
		(fp_line
			(start 0.105328 0.001008)
			(end 0.24 0.001)
			(stroke
				(width 0.1)
				(type solid)
			)
			(layer "F.SilkS")
		)
		(fp_line
			(start -0.094672 0.001008)
			(end 0.105328 -0.198992)
			(stroke
				(width 0.1)
				(type solid)
			)
			(layer "F.SilkS")
		)
		(fp_line
			(start -0.094672 0.001008)
			(end -0.24 0.001008)
			(stroke
				(width 0.1)
				(type solid)
			)
			(layer "F.SilkS")
		)
		(fp_line
			(start 0.105328 0.201008)
			(end 0.105328 -0.198992)
			(stroke
				(width 0.1)
				(type solid)
			)
			(layer "F.SilkS")
		)
		(fp_line
			(start 0.105328 0.201008)
			(end -0.094672 0.001008)
			(stroke
				(width 0.1)
				(type solid)
			)
			(layer "F.SilkS")
		)
		(fp_line
			(start -0.094672 0.201008)
			(end -0.094672 -0.198992)
			(stroke
				(width 0.1)
				(type solid)
			)
			(layer "F.SilkS")
		)
		(fp_line
			(start 0.22 0.35)
			(end -0.22 0.35)
			(stroke
				(width 0.15)
				(type solid)
			)
			(layer "F.SilkS")
		)
		(fp_rect
			(start 1.25 0.65)
			(end -1.25 -0.65)
			(stroke
				(width 0.05)
				(type solid)
			)
			(fill no)
			(layer "F.CrtYd")
		)
		(fp_line
			(start 0.201 -0.202)
			(end -0.101 0)
			(stroke
				(width 0.15)
				(type solid)
			)
			(layer "F.Fab")
		)
		(fp_line
			(start -0.199 -0.202)
			(end -0.199 0.1)
			(stroke
				(width 0.15)
				(type solid)
			)
			(layer "F.Fab")
		)
		(fp_line
			(start 0.599 0)
			(end 0.201 0)
			(stroke
				(width 0.15)
				(type solid)
			)
			(layer "F.Fab")
		)
		(fp_line
			(start 0.201 0)
			(end 0.201 -0.202)
			(stroke
				(width 0.15)
				(type solid)
			)
			(layer "F.Fab")
		)
		(fp_line
			(start -0.101 0)
			(end 0.201 0.2)
			(stroke
				(width 0.15)
				(type solid)
			)
			(layer "F.Fab")
		)
		(fp_line
			(start -0.199 0)
			(end -0.597 0)
			(stroke
				(width 0.15)
				(type solid)
			)
			(layer "F.Fab")
		)
		(fp_line
			(start 0.201 0.2)
			(end 0.201 0)
			(stroke
				(width 0.15)
				(type solid)
			)
			(layer "F.Fab")
		)
		(fp_line
			(start -0.199 0.2)
			(end -0.199 0.1)
			(stroke
				(width 0.15)
				(type solid)
			)
			(layer "F.Fab")
		)
		(fp_rect
			(start 0.848 0.4)
			(end -0.85 -0.402)
			(stroke
				(width 0.15)
				(type solid)
			)
			(fill no)
			(layer "F.Fab")
		)
		(pad "1" smd roundrect
			(at -0.7 0 270)
			(size 0.8 1)
			(layers "F.Cu" "F.Mask" "F.Paste")
			(roundrect_rratio 0.2)
			(net 27 "POWER_OK2")
			(pinfunction "C")
			(pintype "passive")
		)
		(pad "2" smd roundrect
			(at 0.7 0 270)
			(size 0.8 1)
			(layers "F.Cu" "F.Mask" "F.Paste")
			(roundrect_rratio 0.2)
			(net 66 "Net-(D6-A)")
			(pinfunction "A")
			(pintype "passive")
		)
	)
	(footprint "antmicro-footprints:C_0402_1005Metric"
		(layer "F.Cu")
		(at 100.5 88.6)
		(descr "Capacitor SMD 0402")
		(tags "capacitor SMD 0402")
		(property "Reference" "C14"
			(at 2.7 1.8 90)
			(layer "F.SilkS")
			(effects
				(font
					(size 0.7 0.7)
					(thickness 0.15)
				)
				(justify left bottom)
			)
		)
		(property "Value" "C_1n2_50V_0402"
			(at -1.022927 2.155213 0)
			(layer "F.Fab")
			(effects
				(font
					(size 0.7 0.7)
					(thickness 0.15)
				)
				(justify left bottom)
			)
		)
		(property "Datasheet" "https://www.murata.com/products/productdetail?partno=GCM155R71H122KA37%23"
			(at 0 0 0)
			(layer "F.Fab")
			(hide yes)
			(effects
				(font
					(size 1.27 1.27)
					(thickness 0.15)
				)
			)
		)
		(property "Description" "SMD Multilayer Ceramic Capacitor, 1200 pF, 50 V, 0402 [1005 Metric], ± 10%, X7R, GCM"
			(at 0 0 0)
			(layer "F.Fab")
			(hide yes)
			(effects
				(font
					(size 1.27 1.27)
					(thickness 0.15)
				)
			)
		)
		(property "Manufacturer" "Murata"
			(at 0 0 0)
			(unlocked yes)
			(layer "F.Fab")
			(hide yes)
			(effects
				(font
					(size 1 1)
					(thickness 0.15)
				)
			)
		)
		(property "MPN" "GCM155R71H122KA37D"
			(at 0 0 0)
			(unlocked yes)
			(layer "F.Fab")
			(hide yes)
			(effects
				(font
					(size 1 1)
					(thickness 0.15)
				)
			)
		)
		(property "Val" "1n2"
			(at 0 0 0)
			(unlocked yes)
			(layer "F.Fab")
			(hide yes)
			(effects
				(font
					(size 1 1)
					(thickness 0.15)
				)
			)
		)
		(property "License" "Apache-2.0"
			(at 0 0 0)
			(unlocked yes)
			(layer "F.Fab")
			(hide yes)
			(effects
				(font
					(size 1 1)
					(thickness 0.15)
				)
			)
		)
		(property "Author" "Antmicro"
			(at 0 0 0)
			(unlocked yes)
			(layer "F.Fab")
			(hide yes)
			(effects
				(font
					(size 1 1)
					(thickness 0.15)
				)
			)
		)
		(property "Voltage" "50V"
			(at 0 0 0)
			(unlocked yes)
			(layer "F.Fab")
			(hide yes)
			(effects
				(font
					(size 1 1)
					(thickness 0.15)
				)
			)
		)
		(property "Dielectric" ""
			(at 0 0 0)
			(unlocked yes)
			(layer "F.Fab")
			(hide yes)
			(effects
				(font
					(size 1 1)
					(thickness 0.15)
				)
			)
		)
		(sheetname "/DC-DC Converters/")
		(sheetfile "dc-dc_converters.kicad_sch")
		(attr smd exclude_from_pos_files exclude_from_bom dnp)
		(fp_rect
			(start -0.925 -0.47)
			(end 0.925 0.47)
			(stroke
				(width 0.05)
				(type default)
			)
			(fill no)
			(layer "F.CrtYd")
		)
		(fp_line
			(start -0.494 -0.25)
			(end 0.504 -0.25)
			(stroke
				(width 0.15)
				(type solid)
			)
			(layer "F.Fab")
		)
		(fp_line
			(start -0.494 0.248)
			(end -0.494 -0.25)
			(stroke
				(width 0.15)
				(type solid)
			)
			(layer "F.Fab")
		)
		(fp_line
			(start 0.504 -0.25)
			(end 0.504 0.248)
			(stroke
				(width 0.15)
				(type solid)
			)
			(layer "F.Fab")
		)
		(fp_line
			(start 0.504 0.248)
			(end -0.494 0.248)
			(stroke
				(width 0.15)
				(type solid)
			)
			(layer "F.Fab")
		)
		(pad "1" smd roundrect
			(at -0.48 0)
			(size 0.59 0.64)
			(layers "F.Cu" "F.Mask" "F.Paste")
			(roundrect_rratio 0.25)
			(net 19 "/DC-DC Converters/12V_SNS")
			(pintype "passive")
		)
		(pad "2" smd roundrect
			(at 0.48 0)
			(size 0.59 0.64)
			(layers "F.Cu" "F.Mask" "F.Paste")
			(roundrect_rratio 0.25)
			(net 5 "+12V")
			(pintype "passive")
		)
	)
)
